# T6G (Grand Teton) — schematic netlist excerpt (pin names and nets, part order shuffled) for the footprints in the layout excerpt that follows; sources: Cadence DE-HDL packaged netlist, KiCad conversion of 04192023_DAF0TMB3IC0_F0TG_MB_C_brd_V02_OCP.brd

R777  Q_RES  54.9K 1% CHIP  pkg 0402LF  page 108 : A = PD_CHK_CPU1_DIMM_SAA ; B = GND
R395  Q_RES  0 5% CHIP  pkg 0402LF  page 81 : A = FM_SPD_CPU0_SWITCH_CTRL_R_N ; B = FM_SPD_CPU0_SWITCH_CTRL_N

(kicad_pcb
	(version 20260206)
	(generator "pcbnew")
	(generator_version "10.0")
	(general
		(thickness 1.6)
		(legacy_teardrops no)
	)
	(paper "A4")
	(title_block
		(title "04192023_DAF0TMB3IC0_F0TG_MB_C_brd_V02_OCP.brd")
		(comment 1 "Grand Teton / footprints 6890-6891 of 8354")
	)
	(layers
		(0 "F.Cu" signal "TOP")
		(4 "In1.Cu" signal "GND")
		(6 "In2.Cu" signal "IN1")
		(8 "In3.Cu" signal "GND1")
		(10 "In4.Cu" signal "IN2")
		(12 "In5.Cu" signal "GND2")
		(14 "In6.Cu" signal "IN3")
		(16 "In7.Cu" signal "GND3")
		(18 "In8.Cu" signal "VCC")
		(20 "In9.Cu" signal "VCC1")
		(22 "In10.Cu" signal "GND4")
		(24 "In11.Cu" signal "IN4")
		(26 "In12.Cu" signal "GND5")
		(28 "In13.Cu" signal "IN5")
		(30 "In14.Cu" signal "GND6")
		(32 "In15.Cu" signal "IN6")
		(34 "In16.Cu" signal "GND7")
		(2 "B.Cu" signal "BOTTOM")
		(9 "F.Adhes" user "F.Adhesive")
		(11 "B.Adhes" user "B.Adhesive")
		(13 "F.Paste" user "Package Geometry/Pastemask Top")
		(15 "B.Paste" user "Package Geometry/Pastemask Bottom")
		(5 "F.SilkS" user "Ref Des/Silkscreen Top")
		(7 "B.SilkS" user "Ref Des/Silkscreen Bottom")
		(1 "F.Mask" user "Board Geometry/Soldermask Top")
		(3 "B.Mask" user "Board Geometry/Soldermask Bottom")
		(17 "Dwgs.User" user "User.Drawings")
		(19 "Cmts.User" user "User.Comments")
		(21 "Eco1.User" user "User.Eco1")
		(23 "Eco2.User" user "User.Eco2")
		(25 "Edge.Cuts" user "Board Geometry/Outline")
		(27 "Margin" user)
		(31 "F.CrtYd" user "Package Geometry/Place Bound Top")
		(29 "B.CrtYd" user "Package Geometry/Place Bound Bottom")
		(35 "F.Fab" user "Ref Des/Assembly Top")
		(33 "B.Fab" user "Ref Des/Assembly Bottom")
	)
	(footprint ""
		(layer "B.Cu")
		(at 193.205608 -126.833376 -90)
		(property "Reference" "R395"
			(at 0 0 90)
			(layer "B.SilkS")
			(hide yes)
			(effects
				(font
					(size 1.27 1.27)
				)
				(justify mirror)
			)
		)
		(property "Value" ""
			(at 0 0 90)
			(layer "B.Fab")
			(effects
				(font
					(size 1.27 1.27)
				)
				(justify mirror)
			)
		)
		(duplicate_pad_numbers_are_jumpers no)
		(fp_line
			(start -0.7874 0.4064)
			(end 0.7874 0.4064)
			(stroke
				(width 0.1524)
				(type default)
			)
			(layer "B.SilkS")
		)
		(fp_line
			(start 0.7874 0.4064)
			(end 0.7874 -0.4064)
			(stroke
				(width 0.1524)
				(type default)
			)
			(layer "B.SilkS")
		)
		(fp_line
			(start -0.7874 -0.4064)
			(end -0.7874 0.4064)
			(stroke
				(width 0.1524)
				(type default)
			)
			(layer "B.SilkS")
		)
		(fp_line
			(start 0.7874 -0.4064)
			(end -0.7874 -0.4064)
			(stroke
				(width 0.1524)
				(type default)
			)
			(layer "B.SilkS")
		)
		(fp_line
			(start -0.67945 0.3048)
			(end -0.120396 0.3048)
			(stroke
				(width 0.1)
				(type default)
			)
			(layer "B.Fab")
		)
		(fp_line
			(start -0.120396 0.3048)
			(end -0.120396 0.2794)
			(stroke
				(width 0.1)
				(type default)
			)
			(layer "B.Fab")
		)
		(fp_line
			(start 0.12065 0.3048)
			(end 0.67945 0.3048)
			(stroke
				(width 0.1)
				(type default)
			)
			(layer "B.Fab")
		)
		(fp_line
			(start 0.67945 0.3048)
			(end 0.67945 -0.305054)
			(stroke
				(width 0.1)
				(type default)
			)
			(layer "B.Fab")
		)
		(fp_line
			(start -0.120396 0.2794)
			(end 0.12065 0.2794)
			(stroke
				(width 0.1)
				(type default)
			)
			(layer "B.Fab")
		)
		(fp_line
			(start 0.12065 0.2794)
			(end 0.12065 0.3048)
			(stroke
				(width 0.1)
				(type default)
			)
			(layer "B.Fab")
		)
		(fp_line
			(start -0.12065 -0.2794)
			(end -0.12065 -0.3048)
			(stroke
				(width 0.1)
				(type default)
			)
			(layer "B.Fab")
		)
		(fp_line
			(start 0.12065 -0.2794)
			(end -0.12065 -0.2794)
			(stroke
				(width 0.1)
				(type default)
			)
			(layer "B.Fab")
		)
		(fp_line
			(start -0.67945 -0.3048)
			(end -0.67945 0.3048)
			(stroke
				(width 0.1)
				(type default)
			)
			(layer "B.Fab")
		)
		(fp_line
			(start -0.12065 -0.3048)
			(end -0.67945 -0.3048)
			(stroke
				(width 0.1)
				(type default)
			)
			(layer "B.Fab")
		)
		(fp_line
			(start 0.12065 -0.305054)
			(end 0.12065 -0.2794)
			(stroke
				(width 0.1)
				(type default)
			)
			(layer "B.Fab")
		)
		(fp_line
			(start 0.67945 -0.305054)
			(end 0.12065 -0.305054)
			(stroke
				(width 0.1)
				(type default)
			)
			(layer "B.Fab")
		)
		(pad "1" smd circle
			(at 0.40005 0 90)
			(size 0 0)
			(layers "B.Cu" "B.Mask" "B.Paste")
			(net "FM_SPD_CPU0_SWITCH_CTRL_R_N")
		)
		(pad "2" smd circle
			(at -0.40005 0 90)
			(size 0 0)
			(layers "B.Cu" "B.Mask" "B.Paste")
			(net "FM_SPD_CPU0_SWITCH_CTRL_N")
		)
	)
	(footprint ""
		(layer "B.Cu")
		(at 195.359782 -194.885564 180)
		(property "Reference" "R777"
			(at 0 0 0)
			(layer "B.SilkS")
			(hide yes)
			(effects
				(font
					(size 1.27 1.27)
				)
				(justify mirror)
			)
		)
		(property "Value" ""
			(at 0 0 0)
			(layer "B.Fab")
			(effects
				(font
					(size 1.27 1.27)
				)
				(justify mirror)
			)
		)
		(duplicate_pad_numbers_are_jumpers no)
		(fp_line
			(start 0.7874 0.4064)
			(end 0.7874 -0.4064)
			(stroke
				(width 0.1524)
				(type default)
			)
			(layer "B.SilkS")
		)
		(fp_line
			(start 0.7874 -0.4064)
			(end -0.7874 -0.4064)
			(stroke
				(width 0.1524)
				(type default)
			)
			(layer "B.SilkS")
		)
		(fp_line
			(start -0.7874 0.4064)
			(end 0.7874 0.4064)
			(stroke
				(width 0.1524)
				(type default)
			)
			(layer "B.SilkS")
		)
		(fp_line
			(start -0.7874 -0.4064)
			(end -0.7874 0.4064)
			(stroke
				(width 0.1524)
				(type default)
			)
			(layer "B.SilkS")
		)
		(fp_line
			(start 0.67945 0.3048)
			(end 0.67945 -0.305054)
			(stroke
				(width 0.1)
				(type default)
			)
			(layer "B.Fab")
		)
		(fp_line
			(start 0.67945 -0.305054)
			(end 0.12065 -0.305054)
			(stroke
				(width 0.1)
				(type default)
			)
			(layer "B.Fab")
		)
		(fp_line
			(start 0.12065 0.3048)
			(end 0.67945 0.3048)
			(stroke
				(width 0.1)
				(type default)
			)
			(layer "B.Fab")
		)
		(fp_line
			(start 0.12065 0.2794)
			(end 0.12065 0.3048)
			(stroke
				(width 0.1)
				(type default)
			)
			(layer "B.Fab")
		)
		(fp_line
			(start 0.12065 -0.2794)
			(end -0.12065 -0.2794)
			(stroke
				(width 0.1)
				(type default)
			)
			(layer "B.Fab")
		)
		(fp_line
			(start 0.12065 -0.305054)
			(end 0.12065 -0.2794)
			(stroke
				(width 0.1)
				(type default)
			)
			(layer "B.Fab")
		)
		(fp_line
			(start -0.120396 0.3048)
			(end -0.120396 0.2794)
			(stroke
				(width 0.1)
				(type default)
			)
			(layer "B.Fab")
		)
		(fp_line
			(start -0.120396 0.2794)
			(end 0.12065 0.2794)
			(stroke
				(width 0.1)
				(type default)
			)
			(layer "B.Fab")
		)
		(fp_line
			(start -0.12065 -0.2794)
			(end -0.12065 -0.3048)
			(stroke
				(width 0.1)
				(type default)
			)
			(layer "B.Fab")
		)
		(fp_line
			(start -0.12065 -0.3048)
			(end -0.67945 -0.3048)
			(stroke
				(width 0.1)
				(type default)
			)
			(layer "B.Fab")
		)
		(fp_line
			(start -0.67945 0.3048)
			(end -0.120396 0.3048)
			(stroke
				(width 0.1)
				(type default)
			)
			(layer "B.Fab")
		)
		(fp_line
			(start -0.67945 -0.3048)
			(end -0.67945 0.3048)
			(stroke
				(width 0.1)
				(type default)
			)
			(layer "B.Fab")
		)
		(pad "1" smd circle
			(at 0.40005 0)
			(size 0 0)
			(layers "B.Cu" "B.Mask" "B.Paste")
			(net "PD_CHK_CPU1_DIMM_SAA")
		)
		(pad "2" smd circle
			(at -0.40005 0)
			(size 0 0)
			(layers "B.Cu" "B.Mask" "B.Paste")
			(net "GND")
		)
	)
)
